# S9S_MB_2U (Grand Teton) — schematic netlist excerpt (pin names and nets, part order shuffled) for the footprints in the layout excerpt that follows; sources: Cadence DE-HDL packaged netlist, KiCad conversion of 03242023_DA0F0TMBIJ0_F0T_Motherboard_J_brd_V01_OCP.brd

R1312  Q_RES  10K 1% EMPTY  pkg 0402LF  page 220 : A = FM_RST_PERST_BIT2 ; B = GND
PC451_P1_2  Q_CAP  22UF 16V 20% X6S  pkg C0805  page 293 : A = SW_P12V_PVCCINFAON_CPU1_FLT ; B = GND
R328  Q_RES  100 1% CHIP  pkg 0402LF  page 14 : A = SVID_DIO0_CPU0_R ; B = PVNN_TERM_CPU0

(kicad_pcb
	(version 20260206)
	(generator "pcbnew")
	(generator_version "10.0")
	(general
		(thickness 1.6)
		(legacy_teardrops no)
	)
	(paper "A4")
	(title_block
		(title "03242023_DA0F0TMBIJ0_F0T_Motherboard_J_brd_V01_OCP.brd")
		(comment 1 "Grand Teton / footprints 6095-6097 of 6105")
	)
	(layers
		(0 "F.Cu" signal "TOP")
		(4 "In1.Cu" signal "GND")
		(6 "In2.Cu" signal "IN1")
		(8 "In3.Cu" signal "GND1")
		(10 "In4.Cu" signal "IN2")
		(12 "In5.Cu" signal "GND2")
		(14 "In6.Cu" signal "IN3")
		(16 "In7.Cu" signal "GND3")
		(18 "In8.Cu" signal "VCC")
		(20 "In9.Cu" signal "VCC1")
		(22 "In10.Cu" signal "GND4")
		(24 "In11.Cu" signal "IN4")
		(26 "In12.Cu" signal "GND5")
		(28 "In13.Cu" signal "IN5")
		(30 "In14.Cu" signal "GND6")
		(32 "In15.Cu" signal "IN6")
		(34 "In16.Cu" signal "GND7")
		(2 "B.Cu" signal "BOTTOM")
		(9 "F.Adhes" user "F.Adhesive")
		(11 "B.Adhes" user "B.Adhesive")
		(13 "F.Paste" user "Package Geometry/Pastemask Top")
		(15 "B.Paste" user "Package Geometry/Pastemask Bottom")
		(5 "F.SilkS" user "Ref Des/Silkscreen Top")
		(7 "B.SilkS" user "Ref Des/Silkscreen Bottom")
		(1 "F.Mask" user "Board Geometry/Soldermask Top")
		(3 "B.Mask" user "Board Geometry/Soldermask Bottom")
		(17 "Dwgs.User" user "User.Drawings")
		(19 "Cmts.User" user "User.Comments")
		(21 "Eco1.User" user "User.Eco1")
		(23 "Eco2.User" user "User.Eco2")
		(25 "Edge.Cuts" user "Board Geometry/Outline")
		(27 "Margin" user)
		(31 "F.CrtYd" user "Package Geometry/Place Bound Top")
		(29 "B.CrtYd" user "Package Geometry/Place Bound Bottom")
		(35 "F.Fab" user "Ref Des/Assembly Top")
		(33 "B.Fab" user "Ref Des/Assembly Bottom")
	)
	(footprint ""
		(layer "B.Cu")
		(at 193.60388 -106.225848 180)
		(property "Reference" "R1312"
			(at 0 0 0)
			(layer "B.SilkS")
			(hide yes)
			(effects
				(font
					(size 1.27 1.27)
				)
				(justify mirror)
			)
		)
		(property "Value" ""
			(at 0 0 0)
			(layer "B.Fab")
			(effects
				(font
					(size 1.27 1.27)
				)
				(justify mirror)
			)
		)
		(duplicate_pad_numbers_are_jumpers no)
		(fp_line
			(start 0.7874 0.4064)
			(end 0.7874 -0.4064)
			(stroke
				(width 0.1524)
				(type default)
			)
			(layer "B.SilkS")
		)
		(fp_line
			(start 0.7874 -0.4064)
			(end -0.7874 -0.4064)
			(stroke
				(width 0.1524)
				(type default)
			)
			(layer "B.SilkS")
		)
		(fp_line
			(start -0.7874 0.4064)
			(end 0.7874 0.4064)
			(stroke
				(width 0.1524)
				(type default)
			)
			(layer "B.SilkS")
		)
		(fp_line
			(start -0.7874 -0.4064)
			(end -0.7874 0.4064)
			(stroke
				(width 0.1524)
				(type default)
			)
			(layer "B.SilkS")
		)
		(fp_line
			(start 0.67945 0.3048)
			(end 0.67945 -0.305054)
			(stroke
				(width 0.1)
				(type default)
			)
			(layer "B.Fab")
		)
		(fp_line
			(start 0.67945 -0.305054)
			(end 0.12065 -0.305054)
			(stroke
				(width 0.1)
				(type default)
			)
			(layer "B.Fab")
		)
		(fp_line
			(start 0.12065 0.3048)
			(end 0.67945 0.3048)
			(stroke
				(width 0.1)
				(type default)
			)
			(layer "B.Fab")
		)
		(fp_line
			(start 0.12065 0.2794)
			(end 0.12065 0.3048)
			(stroke
				(width 0.1)
				(type default)
			)
			(layer "B.Fab")
		)
		(fp_line
			(start 0.12065 -0.2794)
			(end -0.12065 -0.2794)
			(stroke
				(width 0.1)
				(type default)
			)
			(layer "B.Fab")
		)
		(fp_line
			(start 0.12065 -0.305054)
			(end 0.12065 -0.2794)
			(stroke
				(width 0.1)
				(type default)
			)
			(layer "B.Fab")
		)
		(fp_line
			(start -0.120396 0.3048)
			(end -0.120396 0.2794)
			(stroke
				(width 0.1)
				(type default)
			)
			(layer "B.Fab")
		)
		(fp_line
			(start -0.120396 0.2794)
			(end 0.12065 0.2794)
			(stroke
				(width 0.1)
				(type default)
			)
			(layer "B.Fab")
		)
		(fp_line
			(start -0.12065 -0.2794)
			(end -0.12065 -0.3048)
			(stroke
				(width 0.1)
				(type default)
			)
			(layer "B.Fab")
		)
		(fp_line
			(start -0.12065 -0.3048)
			(end -0.67945 -0.3048)
			(stroke
				(width 0.1)
				(type default)
			)
			(layer "B.Fab")
		)
		(fp_line
			(start -0.67945 0.3048)
			(end -0.120396 0.3048)
			(stroke
				(width 0.1)
				(type default)
			)
			(layer "B.Fab")
		)
		(fp_line
			(start -0.67945 -0.3048)
			(end -0.67945 0.3048)
			(stroke
				(width 0.1)
				(type default)
			)
			(layer "B.Fab")
		)
		(pad "1" smd circle
			(at 0.40005 0)
			(size 0 0)
			(layers "B.Cu" "B.Mask" "B.Paste")
			(net "FM_RST_PERST_BIT2")
		)
		(pad "2" smd circle
			(at -0.40005 0)
			(size 0 0)
			(layers "B.Cu" "B.Mask" "B.Paste")
			(net "GND")
		)
	)
	(footprint ""
		(layer "B.Cu")
		(at 304.697638 -192.450466 90)
		(property "Reference" "R328"
			(at 0 0 90)
			(layer "B.SilkS")
			(hide yes)
			(effects
				(font
					(size 1.27 1.27)
				)
				(justify mirror)
			)
		)
		(property "Value" ""
			(at 0 0 90)
			(layer "B.Fab")
			(effects
				(font
					(size 1.27 1.27)
				)
				(justify mirror)
			)
		)
		(duplicate_pad_numbers_are_jumpers no)
		(fp_line
			(start 0.7874 -0.4064)
			(end -0.7874 -0.4064)
			(stroke
				(width 0.1524)
				(type default)
			)
			(layer "B.SilkS")
		)
		(fp_line
			(start -0.7874 -0.4064)
			(end -0.7874 0.4064)
			(stroke
				(width 0.1524)
				(type default)
			)
			(layer "B.SilkS")
		)
		(fp_line
			(start 0.7874 0.4064)
			(end 0.7874 -0.4064)
			(stroke
				(width 0.1524)
				(type default)
			)
			(layer "B.SilkS")
		)
		(fp_line
			(start -0.7874 0.4064)
			(end 0.7874 0.4064)
			(stroke
				(width 0.1524)
				(type default)
			)
			(layer "B.SilkS")
		)
		(fp_line
			(start 0.67945 -0.305054)
			(end 0.12065 -0.305054)
			(stroke
				(width 0.1)
				(type default)
			)
			(layer "B.Fab")
		)
		(fp_line
			(start 0.12065 -0.305054)
			(end 0.12065 -0.2794)
			(stroke
				(width 0.1)
				(type default)
			)
			(layer "B.Fab")
		)
		(fp_line
			(start -0.12065 -0.3048)
			(end -0.67945 -0.3048)
			(stroke
				(width 0.1)
				(type default)
			)
			(layer "B.Fab")
		)
		(fp_line
			(start -0.67945 -0.3048)
			(end -0.67945 0.3048)
			(stroke
				(width 0.1)
				(type default)
			)
			(layer "B.Fab")
		)
		(fp_line
			(start 0.12065 -0.2794)
			(end -0.12065 -0.2794)
			(stroke
				(width 0.1)
				(type default)
			)
			(layer "B.Fab")
		)
		(fp_line
			(start -0.12065 -0.2794)
			(end -0.12065 -0.3048)
			(stroke
				(width 0.1)
				(type default)
			)
			(layer "B.Fab")
		)
		(fp_line
			(start 0.12065 0.2794)
			(end 0.12065 0.3048)
			(stroke
				(width 0.1)
				(type default)
			)
			(layer "B.Fab")
		)
		(fp_line
			(start -0.120396 0.2794)
			(end 0.12065 0.2794)
			(stroke
				(width 0.1)
				(type default)
			)
			(layer "B.Fab")
		)
		(fp_line
			(start 0.67945 0.3048)
			(end 0.67945 -0.305054)
			(stroke
				(width 0.1)
				(type default)
			)
			(layer "B.Fab")
		)
		(fp_line
			(start 0.12065 0.3048)
			(end 0.67945 0.3048)
			(stroke
				(width 0.1)
				(type default)
			)
			(layer "B.Fab")
		)
		(fp_line
			(start -0.120396 0.3048)
			(end -0.120396 0.2794)
			(stroke
				(width 0.1)
				(type default)
			)
			(layer "B.Fab")
		)
		(fp_line
			(start -0.67945 0.3048)
			(end -0.120396 0.3048)
			(stroke
				(width 0.1)
				(type default)
			)
			(layer "B.Fab")
		)
		(pad "1" smd circle
			(at 0.40005 0 270)
			(size 0 0)
			(layers "B.Cu" "B.Mask" "B.Paste")
			(net "SVID_DIO0_CPU0_R")
		)
		(pad "2" smd circle
			(at -0.40005 0 270)
			(size 0 0)
			(layers "B.Cu" "B.Mask" "B.Paste")
			(net "PVNN_TERM_CPU0")
		)
	)
	(footprint ""
		(layer "B.Cu")
		(at 54.880002 -148.963634 180)
		(property "Reference" "PC451_P1_2"
			(at 0 0 0)
			(layer "B.SilkS")
			(hide yes)
			(effects
				(font
					(size 1.27 1.27)
				)
				(justify mirror)
			)
		)
		(property "Value" ""
			(at 0 0 0)
			(layer "B.Fab")
			(effects
				(font
					(size 1.27 1.27)
				)
				(justify mirror)
			)
		)
		(duplicate_pad_numbers_are_jumpers no)
		(fp_line
			(start 1.524 0.762)
			(end 1.524 -0.762)
			(stroke
				(width 0.1524)
				(type default)
			)
			(layer "B.SilkS")
		)
		(fp_line
			(start 1.524 -0.762)
			(end -1.524 -0.762)
			(stroke
				(width 0.1524)
				(type default)
			)
			(layer "B.SilkS")
		)
		(fp_line
			(start -1.524 0.762)
			(end 1.524 0.762)
			(stroke
				(width 0.1524)
				(type default)
			)
			(layer "B.SilkS")
		)
		(fp_line
			(start -1.524 -0.762)
			(end -1.524 0.762)
			(stroke
				(width 0.1524)
				(type default)
			)
			(layer "B.SilkS")
		)
		(fp_line
			(start 1.1049 0.724916)
			(end -1.1049 0.724916)
			(stroke
				(width 0.1)
				(type default)
			)
			(layer "B.Fab")
		)
		(fp_line
			(start 1.1049 -0.724916)
			(end 1.1049 0.724916)
			(stroke
				(width 0.1)
				(type default)
			)
			(layer "B.Fab")
		)
		(fp_line
			(start -1.1049 0.724916)
			(end -1.1049 -0.724916)
			(stroke
				(width 0.1)
				(type default)
			)
			(layer "B.Fab")
		)
		(fp_line
			(start -1.1049 -0.724916)
			(end 1.1049 -0.724916)
			(stroke
				(width 0.1)
				(type default)
			)
			(layer "B.Fab")
		)
		(pad "1" smd rect
			(at 0.889 0 180)
			(size 1.016 1.27)
			(layers "B.Cu" "B.Mask" "B.Paste")
			(net "SW_P12V_PVCCINFAON_CPU1_FLT")
		)
		(pad "2" smd rect
			(at -0.889 0 180)
			(size 1.016 1.27)
			(layers "B.Cu" "B.Mask" "B.Paste")
			(net "GND")
		)
	)
)
